# T6G (Grand Teton) — schematic netlist excerpt (pin names and nets, part order shuffled) for the footprints in the layout excerpt that follows; sources: Cadence DE-HDL packaged netlist, KiCad conversion of 04192023_DAF0TMB3IC0_F0TG_MB_C_brd_V02_OCP.brd

PC2169  Q_CAP  1UF 25V 10% X6S  pkg C0402  page 141 : A = P3V3_AUX ; B = GND
R4571  Q_RES  0 5% EMPTY  pkg 0402LF  page 124 : A = GPU_3V3IO_RSVD4 ; B = GPU_3V3IO_RSVD4_ISO

(kicad_pcb
	(version 20260206)
	(generator "pcbnew")
	(generator_version "10.0")
	(general
		(thickness 1.6)
		(legacy_teardrops no)
	)
	(paper "A4")
	(title_block
		(title "04192023_DAF0TMB3IC0_F0TG_MB_C_brd_V02_OCP.brd")
		(comment 1 "Grand Teton / footprints 557-558 of 8354")
	)
	(layers
		(0 "F.Cu" signal "TOP")
		(4 "In1.Cu" signal "GND")
		(6 "In2.Cu" signal "IN1")
		(8 "In3.Cu" signal "GND1")
		(10 "In4.Cu" signal "IN2")
		(12 "In5.Cu" signal "GND2")
		(14 "In6.Cu" signal "IN3")
		(16 "In7.Cu" signal "GND3")
		(18 "In8.Cu" signal "VCC")
		(20 "In9.Cu" signal "VCC1")
		(22 "In10.Cu" signal "GND4")
		(24 "In11.Cu" signal "IN4")
		(26 "In12.Cu" signal "GND5")
		(28 "In13.Cu" signal "IN5")
		(30 "In14.Cu" signal "GND6")
		(32 "In15.Cu" signal "IN6")
		(34 "In16.Cu" signal "GND7")
		(2 "B.Cu" signal "BOTTOM")
		(9 "F.Adhes" user "F.Adhesive")
		(11 "B.Adhes" user "B.Adhesive")
		(13 "F.Paste" user "Package Geometry/Pastemask Top")
		(15 "B.Paste" user "Package Geometry/Pastemask Bottom")
		(5 "F.SilkS" user "Ref Des/Silkscreen Top")
		(7 "B.SilkS" user "Ref Des/Silkscreen Bottom")
		(1 "F.Mask" user "Board Geometry/Soldermask Top")
		(3 "B.Mask" user "Board Geometry/Soldermask Bottom")
		(17 "Dwgs.User" user "User.Drawings")
		(19 "Cmts.User" user "User.Comments")
		(21 "Eco1.User" user "User.Eco1")
		(23 "Eco2.User" user "User.Eco2")
		(25 "Edge.Cuts" user "Board Geometry/Outline")
		(27 "Margin" user)
		(31 "F.CrtYd" user "Package Geometry/Place Bound Top")
		(29 "B.CrtYd" user "Package Geometry/Place Bound Bottom")
		(35 "F.Fab" user "Ref Des/Assembly Top")
		(33 "B.Fab" user "Ref Des/Assembly Bottom")
	)
	(footprint ""
		(layer "F.Cu")
		(at 440.088782 -438.14746 -90)
		(property "Reference" "R4571"
			(at 0 0 270)
			(layer "F.SilkS")
			(hide yes)
			(effects
				(font
					(size 1.27 1.27)
				)
			)
		)
		(property "Value" ""
			(at 0 0 270)
			(layer "F.Fab")
			(effects
				(font
					(size 1.27 1.27)
				)
			)
		)
		(duplicate_pad_numbers_are_jumpers no)
		(fp_line
			(start -0.7874 0.4064)
			(end -0.7874 -0.4064)
			(stroke
				(width 0.1524)
				(type default)
			)
			(layer "F.SilkS")
		)
		(fp_line
			(start 0.7874 0.4064)
			(end -0.7874 0.4064)
			(stroke
				(width 0.1524)
				(type default)
			)
			(layer "F.SilkS")
		)
		(fp_line
			(start -0.7874 -0.4064)
			(end 0.7874 -0.4064)
			(stroke
				(width 0.1524)
				(type default)
			)
			(layer "F.SilkS")
		)
		(fp_line
			(start 0.7874 -0.4064)
			(end 0.7874 0.4064)
			(stroke
				(width 0.1524)
				(type default)
			)
			(layer "F.SilkS")
		)
		(fp_line
			(start -0.67945 0.3048)
			(end -0.67945 -0.305054)
			(stroke
				(width 0.1)
				(type default)
			)
			(layer "F.Fab")
		)
		(fp_line
			(start -0.12065 0.3048)
			(end -0.67945 0.3048)
			(stroke
				(width 0.1)
				(type default)
			)
			(layer "F.Fab")
		)
		(fp_line
			(start 0.120396 0.3048)
			(end 0.120396 0.2794)
			(stroke
				(width 0.1)
				(type default)
			)
			(layer "F.Fab")
		)
		(fp_line
			(start 0.67945 0.3048)
			(end 0.120396 0.3048)
			(stroke
				(width 0.1)
				(type default)
			)
			(layer "F.Fab")
		)
		(fp_line
			(start -0.12065 0.2794)
			(end -0.12065 0.3048)
			(stroke
				(width 0.1)
				(type default)
			)
			(layer "F.Fab")
		)
		(fp_line
			(start 0.120396 0.2794)
			(end -0.12065 0.2794)
			(stroke
				(width 0.1)
				(type default)
			)
			(layer "F.Fab")
		)
		(fp_line
			(start -0.12065 -0.2794)
			(end 0.12065 -0.2794)
			(stroke
				(width 0.1)
				(type default)
			)
			(layer "F.Fab")
		)
		(fp_line
			(start 0.12065 -0.2794)
			(end 0.12065 -0.3048)
			(stroke
				(width 0.1)
				(type default)
			)
			(layer "F.Fab")
		)
		(fp_line
			(start 0.12065 -0.3048)
			(end 0.67945 -0.3048)
			(stroke
				(width 0.1)
				(type default)
			)
			(layer "F.Fab")
		)
		(fp_line
			(start 0.67945 -0.3048)
			(end 0.67945 0.3048)
			(stroke
				(width 0.1)
				(type default)
			)
			(layer "F.Fab")
		)
		(fp_line
			(start -0.67945 -0.305054)
			(end -0.12065 -0.305054)
			(stroke
				(width 0.1)
				(type default)
			)
			(layer "F.Fab")
		)
		(fp_line
			(start -0.12065 -0.305054)
			(end -0.12065 -0.2794)
			(stroke
				(width 0.1)
				(type default)
			)
			(layer "F.Fab")
		)
		(pad "1" smd circle
			(at -0.40005 0 270)
			(size 0 0)
			(layers "F.Cu" "F.Mask" "F.Paste")
			(net "GPU_3V3IO_RSVD4")
		)
		(pad "2" smd circle
			(at 0.40005 0 270)
			(size 0 0)
			(layers "F.Cu" "F.Mask" "F.Paste")
			(net "GPU_3V3IO_RSVD4_ISO")
		)
	)
	(footprint ""
		(layer "F.Cu")
		(at 92.559632 -74.68362 180)
		(property "Reference" "PC2169"
			(at 0 0 180)
			(layer "F.SilkS")
			(hide yes)
			(effects
				(font
					(size 1.27 1.27)
				)
			)
		)
		(property "Value" ""
			(at 0 0 180)
			(layer "F.Fab")
			(effects
				(font
					(size 1.27 1.27)
				)
			)
		)
		(duplicate_pad_numbers_are_jumpers no)
		(fp_line
			(start 0.7874 0.4064)
			(end -0.7874 0.4064)
			(stroke
				(width 0.1524)
				(type default)
			)
			(layer "F.SilkS")
		)
		(fp_line
			(start 0.7874 -0.4064)
			(end 0.7874 0.4064)
			(stroke
				(width 0.1524)
				(type default)
			)
			(layer "F.SilkS")
		)
		(fp_line
			(start -0.7874 0.4064)
			(end -0.7874 -0.4064)
			(stroke
				(width 0.1524)
				(type default)
			)
			(layer "F.SilkS")
		)
		(fp_line
			(start -0.7874 -0.4064)
			(end 0.7874 -0.4064)
			(stroke
				(width 0.1524)
				(type default)
			)
			(layer "F.SilkS")
		)
		(fp_line
			(start 0.67945 0.3048)
			(end 0.120396 0.3048)
			(stroke
				(width 0.1)
				(type default)
			)
			(layer "F.Fab")
		)
		(fp_line
			(start 0.67945 -0.3048)
			(end 0.67945 0.3048)
			(stroke
				(width 0.1)
				(type default)
			)
			(layer "F.Fab")
		)
		(fp_line
			(start 0.12065 -0.2794)
			(end 0.12065 -0.3048)
			(stroke
				(width 0.1)
				(type default)
			)
			(layer "F.Fab")
		)
		(fp_line
			(start 0.12065 -0.3048)
			(end 0.67945 -0.3048)
			(stroke
				(width 0.1)
				(type default)
			)
			(layer "F.Fab")
		)
		(fp_line
			(start 0.120396 0.3048)
			(end 0.120396 0.2794)
			(stroke
				(width 0.1)
				(type default)
			)
			(layer "F.Fab")
		)
		(fp_line
			(start 0.120396 0.2794)
			(end -0.12065 0.2794)
			(stroke
				(width 0.1)
				(type default)
			)
			(layer "F.Fab")
		)
		(fp_line
			(start -0.12065 0.3048)
			(end -0.67945 0.3048)
			(stroke
				(width 0.1)
				(type default)
			)
			(layer "F.Fab")
		)
		(fp_line
			(start -0.12065 0.2794)
			(end -0.12065 0.3048)
			(stroke
				(width 0.1)
				(type default)
			)
			(layer "F.Fab")
		)
		(fp_line
			(start -0.12065 -0.2794)
			(end 0.12065 -0.2794)
			(stroke
				(width 0.1)
				(type default)
			)
			(layer "F.Fab")
		)
		(fp_line
			(start -0.12065 -0.305054)
			(end -0.12065 -0.2794)
			(stroke
				(width 0.1)
				(type default)
			)
			(layer "F.Fab")
		)
		(fp_line
			(start -0.67945 0.3048)
			(end -0.67945 -0.305054)
			(stroke
				(width 0.1)
				(type default)
			)
			(layer "F.Fab")
		)
		(fp_line
			(start -0.67945 -0.305054)
			(end -0.12065 -0.305054)
			(stroke
				(width 0.1)
				(type default)
			)
			(layer "F.Fab")
		)
		(pad "1" smd circle
			(at -0.40005 0 180)
			(size 0 0)
			(layers "F.Cu" "F.Mask" "F.Paste")
			(net "P3V3_AUX")
		)
		(pad "2" smd circle
			(at 0.40005 0 180)
			(size 0 0)
			(layers "F.Cu" "F.Mask" "F.Paste")
			(net "GND")
		)
	)
)
